(kicad_pcb
	(version 20260206)
	(generator "pcbnew")
	(generator_version "10.0")
	(general
		(thickness 1.6)
		(legacy_teardrops no)
	)
	(paper "A4")
	(title_block
		(title "Bryce Canyon_F.DPB_16315-1-OCP.brd")
		(comment 1 "Bryce Canyon / footprints 635-640 of 2223")
	)
	(layers
		(0 "F.Cu" signal "TOP")
		(4 "In1.Cu" signal "L2GND")
		(6 "In2.Cu" signal "L3")
		(8 "In3.Cu" signal "L4GND")
		(10 "In4.Cu" signal "L5")
		(12 "In5.Cu" signal "L6VCC")
		(14 "In6.Cu" signal "L7VCC")
		(16 "In7.Cu" signal "L8")
		(18 "In8.Cu" signal "L9GND")
		(20 "In9.Cu" signal "L10")
		(22 "In10.Cu" signal "L11GND")
		(2 "B.Cu" signal "BOTTOM")
		(9 "F.Adhes" user "F.Adhesive")
		(11 "B.Adhes" user "B.Adhesive")
		(13 "F.Paste" user "Package Geometry/Pastemask Top")
		(15 "B.Paste" user "Package Geometry/Pastemask Bottom")
		(5 "F.SilkS" user "Ref Des/Silkscreen Top")
		(7 "B.SilkS" user "Ref Des/Silkscreen Bottom")
		(1 "F.Mask" user "Board Geometry/Soldermask Top")
		(3 "B.Mask" user "Board Geometry/Soldermask Bottom")
		(17 "Dwgs.User" user "User.Drawings")
		(19 "Cmts.User" user "User.Comments")
		(21 "Eco1.User" user "User.Eco1")
		(23 "Eco2.User" user "User.Eco2")
		(25 "Edge.Cuts" user "Board Geometry/Outline")
		(27 "Margin" user)
		(31 "F.CrtYd" user "Package Geometry/Place Bound Top")
		(29 "B.CrtYd" user "Package Geometry/Place Bound Bottom")
		(35 "F.Fab" user "Ref Des/Assembly Top")
		(33 "B.Fab" user "Ref Des/Assembly Bottom")
	)
	(footprint ""
		(layer "F.Cu")
		(at 101.163374 -298.52493)
		(property "Reference" "Q290"
			(at 0 0 0)
			(layer "F.SilkS")
			(hide yes)
			(effects
				(font
					(size 1.27 1.27)
				)
			)
		)
		(property "Value" "SSM3K324R-GP"
			(at 0.127 -8.9662 0)
			(unlocked yes)
			(layer "F.Fab")
			(hide yes)
			(effects
				(font
					(size 1.016 1.016)
					(thickness 0.1524)
				)
			)
		)
		(property "Device Type" "SOT23DGS2D4H35"
			(at 0.127 -10.4902 0)
			(unlocked yes)
			(layer "F.Fab")
			(hide yes)
			(effects
				(font
					(size 1.016 1.016)
					(thickness 0.1524)
				)
			)
		)
		(duplicate_pad_numbers_are_jumpers no)
		(fp_line
			(start -1.651 -1.778)
			(end -1.651 1.778)
			(stroke
				(width 0.1524)
				(type default)
			)
			(layer "F.SilkS")
		)
		(fp_line
			(start -1.651 1.778)
			(end 1.651 1.778)
			(stroke
				(width 0.1524)
				(type default)
			)
			(layer "F.SilkS")
		)
		(fp_line
			(start 1.651 -1.778)
			(end -1.651 -1.778)
			(stroke
				(width 0.1524)
				(type default)
			)
			(layer "F.SilkS")
		)
		(fp_line
			(start 1.651 1.778)
			(end 1.651 -1.778)
			(stroke
				(width 0.1524)
				(type default)
			)
			(layer "F.SilkS")
		)
		(fp_poly
			(pts
				(xy -1.778 1.8796) (xy -1.778 -1.8796) (xy 1.778 -1.8796) (xy 1.778 1.8796)
			)
			(stroke
				(width 0)
				(type default)
			)
			(fill no)
			(layer "F.CrtYd")
		)
		(fp_poly
			(pts
				(xy -1.778 1.8796) (xy -1.778 -1.8796) (xy 1.778 -1.8796) (xy 1.778 1.8796)
			)
			(stroke
				(width 0)
				(type default)
			)
			(fill no)
			(layer "F.Fab")
		)
		(pad "D" smd custom
			(at 0 -0.9525)
			(size 0.1905 0.1905)
			(layers "F.Cu" "F.Mask" "F.Paste")
			(net "DRV_ACT_27_N")
			(options
				(clearance outline)
				(anchor circle)
			)
			(primitives
				(gr_poly
					(pts
						(arc
							(start -0.1778 0.5715)
							(mid -0.321484 0.511984)
							(end -0.381 0.3683)
						)
						(arc
							(start -0.381 -0.3683)
							(mid -0.321484 -0.511984)
							(end -0.1778 -0.5715)
						)
						(arc
							(start 0.1778 -0.5715)
							(mid 0.321484 -0.511984)
							(end 0.381 -0.3683)
						)
						(arc
							(start 0.381 0.3683)
							(mid 0.321484 0.511984)
							(end 0.1778 0.5715)
						)
					)
					(width 0)
					(fill yes)
				)
			)
		)
		(pad "G" smd custom
			(at -0.98425 0.9525)
			(size 0.1905 0.1905)
			(layers "F.Cu" "F.Mask" "F.Paste")
			(net "DRIVE_B_27_ACT")
			(options
				(clearance outline)
				(anchor circle)
			)
			(primitives
				(gr_poly
					(pts
						(arc
							(start -0.1778 0.5715)
							(mid -0.321484 0.511984)
							(end -0.381 0.3683)
						)
						(arc
							(start -0.381 -0.3683)
							(mid -0.321484 -0.511984)
							(end -0.1778 -0.5715)
						)
						(arc
							(start 0.1778 -0.5715)
							(mid 0.321484 -0.511984)
							(end 0.381 -0.3683)
						)
						(arc
							(start 0.381 0.3683)
							(mid 0.321484 0.511984)
							(end 0.1778 0.5715)
						)
					)
					(width 0)
					(fill yes)
				)
			)
		)
		(pad "S" smd custom
			(at 0.98425 0.9525)
			(size 0.1905 0.1905)
			(layers "F.Cu" "F.Mask" "F.Paste")
			(net "GND")
			(options
				(clearance outline)
				(anchor circle)
			)
			(primitives
				(gr_poly
					(pts
						(arc
							(start -0.1778 0.5715)
							(mid -0.321484 0.511984)
							(end -0.381 0.3683)
						)
						(arc
							(start -0.381 -0.3683)
							(mid -0.321484 -0.511984)
							(end -0.1778 -0.5715)
						)
						(arc
							(start 0.1778 -0.5715)
							(mid 0.321484 -0.511984)
							(end 0.381 -0.3683)
						)
						(arc
							(start 0.381 0.3683)
							(mid 0.321484 0.511984)
							(end 0.1778 0.5715)
						)
					)
					(width 0)
					(fill yes)
				)
			)
		)
	)
	(footprint ""
		(layer "F.Cu")
		(at 338.709 -171.809918 -90)
		(property "Reference" "R559"
			(at 0 0 270)
			(layer "F.SilkS")
			(hide yes)
			(effects
				(font
					(size 1.27 1.27)
				)
			)
		)
		(property "Value" "300KR2F-GP"
			(at 0.064008 -3.993896 270)
			(unlocked yes)
			(layer "F.Fab")
			(hide yes)
			(effects
				(font
					(size 1.016 1.016)
					(thickness 0.1524)
				)
			)
		)
		(property "Device Type" "R402H16"
			(at 0.064008 -5.517896 270)
			(unlocked yes)
			(layer "F.Fab")
			(hide yes)
			(effects
				(font
					(size 1.016 1.016)
					(thickness 0.1524)
				)
			)
		)
		(duplicate_pad_numbers_are_jumpers no)
		(fp_line
			(start -0.508 -0.9398)
			(end -0.508 0.9398)
			(stroke
				(width 0.1524)
				(type default)
			)
			(layer "F.SilkS")
		)
		(fp_line
			(start 0.508 -0.9398)
			(end -0.508 -0.9398)
			(stroke
				(width 0.1524)
				(type default)
			)
			(layer "F.SilkS")
		)
		(fp_rect
			(start -0.508 0.9398)
			(end 0.508 -0.9398)
			(stroke
				(width 0)
				(type default)
			)
			(fill no)
			(layer "F.CrtYd")
		)
		(fp_rect
			(start -0.508 0.9398)
			(end 0.508 -0.9398)
			(stroke
				(width 0)
				(type default)
			)
			(fill no)
			(layer "F.Fab")
		)
		(pad "1" smd custom
			(at 0 -0.4445 270)
			(size 0.1397 0.1397)
			(layers "F.Cu" "F.Mask" "F.Paste")
			(net "SW_HDD_N18")
			(options
				(clearance outline)
				(anchor circle)
			)
			(primitives
				(gr_poly
					(pts
						(arc
							(start -0.1778 -0.2794)
							(mid -0.249642 -0.249642)
							(end -0.2794 -0.1778)
						)
						(arc
							(start -0.2794 0.1778)
							(mid -0.249642 0.249642)
							(end -0.1778 0.2794)
						)
						(arc
							(start 0.1778 0.2794)
							(mid 0.249642 0.249642)
							(end 0.2794 0.1778)
						)
						(arc
							(start 0.2794 -0.1778)
							(mid 0.249642 -0.249642)
							(end 0.1778 -0.2794)
						)
					)
					(width 0)
					(fill yes)
				)
			)
		)
		(pad "2" smd custom
			(at 0 0.4445 270)
			(size 0.1397 0.1397)
			(layers "F.Cu" "F.Mask" "F.Paste")
			(net "P12V_A")
			(options
				(clearance outline)
				(anchor circle)
			)
			(primitives
				(gr_poly
					(pts
						(arc
							(start -0.1778 -0.2794)
							(mid -0.249642 -0.249642)
							(end -0.2794 -0.1778)
						)
						(arc
							(start -0.2794 0.1778)
							(mid -0.249642 0.249642)
							(end -0.1778 0.2794)
						)
						(arc
							(start 0.1778 0.2794)
							(mid 0.249642 0.249642)
							(end 0.2794 0.1778)
						)
						(arc
							(start 0.2794 -0.1778)
							(mid 0.249642 -0.249642)
							(end 0.1778 -0.2794)
						)
					)
					(width 0)
					(fill yes)
				)
			)
		)
	)
	(footprint ""
		(layer "F.Cu")
		(at 202.300078 -63.805562)
		(property "Reference" ""
			(at 0 0 0)
			(layer "F.SilkS")
			(hide yes)
			(effects
				(font
					(size 1.27 1.27)
				)
			)
		)
		(property "Value" "*"
			(at -8.398764 -8.057642 0)
			(unlocked yes)
			(layer "F.Fab")
			(hide yes)
			(effects
				(font
					(size 1.016 1.016)
					(thickness 0.1524)
				)
			)
		)
		(duplicate_pad_numbers_are_jumpers no)
		(fp_poly
			(pts
				(arc
					(start 7.3152 0)
					(mid 0 7.3152)
					(end -7.3152 0)
				)
				(arc
					(start -7.3152 -5.9944)
					(mid 0 -13.3096)
					(end 7.3152 -5.9944)
				)
			)
			(stroke
				(width 0)
				(type default)
			)
			(fill no)
			(layer "B.CrtYd")
		)
		(fp_poly
			(pts
				(arc
					(start 7.3152 0)
					(mid 0 7.3152)
					(end -7.3152 0)
				)
				(arc
					(start -7.3152 -5.9944)
					(mid 0 -13.3096)
					(end 7.3152 -5.9944)
				)
			)
			(stroke
				(width 0)
				(type default)
			)
			(fill no)
			(layer "F.CrtYd")
		)
		(fp_poly
			(pts
				(arc
					(start 7.3152 0)
					(mid 0 7.3152)
					(end -7.3152 0)
				)
				(arc
					(start -7.3152 -5.9944)
					(mid 0 -13.3096)
					(end 7.3152 -5.9944)
				)
			)
			(stroke
				(width 0)
				(type default)
			)
			(fill no)
			(layer "B.Fab")
		)
		(fp_poly
			(pts
				(arc
					(start 7.3152 0)
					(mid 0 7.3152)
					(end -7.3152 0)
				)
				(arc
					(start -7.3152 -5.9944)
					(mid 0 -13.3096)
					(end 7.3152 -5.9944)
				)
			)
			(stroke
				(width 0)
				(type default)
			)
			(fill no)
			(layer "F.Fab")
		)
		(pad "1" thru_hole oval
			(at 0 0)
			(size 14.0208 20.0152)
			(drill 0.0254
				(offset 0 -2.9972)
			)
			(layers "*.Cu" "*.Mask")
			(remove_unused_layers no)
			(net "Net_35")
			(clearance -1.002284)
			(thermal_gap 0.1524)
			(padstack
				(mode front_inner_back)
				(layer "Inner"
					(shape custom)
					(size 2.928012 2.928012)
					(options
						(anchor circle)
					)
					(primitives
						(gr_poly
							(pts
								(arc
									(start 4.571746 -2.084324)
									(mid 0.000333 7.430372)
									(end -4.571492 -2.084324)
								)
								(arc
									(start -4.571492 -2.084324)
									(mid -3.570296 -3.611977)
									(end -2.875026 -5.30098)
								)
								(arc
									(start -2.875026 -5.30098)
									(mid 0.000217 -7.43089)
									(end 2.87528 -5.30098)
								)
								(arc
									(start 2.87528 -5.30098)
									(mid 3.570511 -3.611956)
									(end 4.571746 -2.084324)
								)
							)
							(width 0)
							(fill yes)
						)
					)
					(clearance 0.1524)
				)
				(layer "B.Cu"
					(shape oval)
					(size 14.0208 20.0152)
					(offset 0 -2.9972)
					(clearance -1.002284)
				)
			)
		)
		(zone
			(layers "F.Cu" "B.Cu" "In1.Cu" "In2.Cu" "In3.Cu" "In4.Cu" "In5.Cu" "In6.Cu"
				"In7.Cu" "In8.Cu" "In9.Cu" "In10.Cu"
			)
			(hatch none 0.5)
			(connect_pads
				(clearance 0)
			)
			(min_thickness 0.25)
			(keepout
				(tracks not_allowed)
				(vias allowed)
				(pads allowed)
				(copperpour not_allowed)
				(footprints allowed)
			)
			(placement
				(enabled no)
				(sheetname "")
			)
			(fill
				(thermal_gap 0.5)
				(thermal_bridge_width 0.5)
				(island_removal_mode 0)
			)
			(polygon
				(pts
					(arc
						(start 195.289678 -69.799962)
						(mid 202.300078 -76.810362)
						(end 209.310478 -69.799962)
					)
					(arc
						(start 209.310478 -63.805562)
						(mid 202.300078 -56.795162)
						(end 195.289678 -63.805562)
					)
				)
			)
		)
	)
	(footprint ""
		(layer "F.Cu")
		(at 14.817598 -45.608494 90)
		(property "Reference" "R696"
			(at 0 0 90)
			(layer "F.SilkS")
			(hide yes)
			(effects
				(font
					(size 1.27 1.27)
				)
			)
		)
		(property "Value" "4K7R2J-2-GP"
			(at 0.064008 -3.993896 90)
			(unlocked yes)
			(layer "F.Fab")
			(hide yes)
			(effects
				(font
					(size 1.016 1.016)
					(thickness 0.1524)
				)
			)
		)
		(property "Device Type" "R402H16"
			(at 0.064008 -5.517896 90)
			(unlocked yes)
			(layer "F.Fab")
			(hide yes)
			(effects
				(font
					(size 1.016 1.016)
					(thickness 0.1524)
				)
			)
		)
		(duplicate_pad_numbers_are_jumpers no)
		(fp_line
			(start 0.508 -0.9398)
			(end -0.508 -0.9398)
			(stroke
				(width 0.1524)
				(type default)
			)
			(layer "F.SilkS")
		)
		(fp_line
			(start -0.508 -0.9398)
			(end -0.508 0.9398)
			(stroke
				(width 0.1524)
				(type default)
			)
			(layer "F.SilkS")
		)
		(fp_rect
			(start -0.508 0.9398)
			(end 0.508 -0.9398)
			(stroke
				(width 0)
				(type default)
			)
			(fill no)
			(layer "F.CrtYd")
		)
		(fp_rect
			(start -0.508 0.9398)
			(end 0.508 -0.9398)
			(stroke
				(width 0)
				(type default)
			)
			(fill no)
			(layer "F.Fab")
		)
		(pad "1" smd custom
			(at 0 -0.4445 90)
			(size 0.1397 0.1397)
			(layers "F.Cu" "F.Mask" "F.Paste")
			(net "P12V_A")
			(options
				(clearance outline)
				(anchor circle)
			)
			(primitives
				(gr_poly
					(pts
						(arc
							(start -0.1778 -0.2794)
							(mid -0.249642 -0.249642)
							(end -0.2794 -0.1778)
						)
						(arc
							(start -0.2794 0.1778)
							(mid -0.249642 0.249642)
							(end -0.1778 0.2794)
						)
						(arc
							(start 0.1778 0.2794)
							(mid 0.249642 0.249642)
							(end 0.2794 0.1778)
						)
						(arc
							(start 0.2794 -0.1778)
							(mid 0.249642 -0.249642)
							(end 0.1778 -0.2794)
						)
					)
					(width 0)
					(fill yes)
				)
			)
		)
		(pad "2" smd custom
			(at 0 0.4445 90)
			(size 0.1397 0.1397)
			(layers "F.Cu" "F.Mask" "F.Paste")
			(net "SW_HDD_R24")
			(options
				(clearance outline)
				(anchor circle)
			)
			(primitives
				(gr_poly
					(pts
						(arc
							(start -0.1778 -0.2794)
							(mid -0.249642 -0.249642)
							(end -0.2794 -0.1778)
						)
						(arc
							(start -0.2794 0.1778)
							(mid -0.249642 0.249642)
							(end -0.1778 0.2794)
						)
						(arc
							(start 0.1778 0.2794)
							(mid 0.249642 0.249642)
							(end 0.2794 0.1778)
						)
						(arc
							(start 0.2794 -0.1778)
							(mid 0.249642 -0.249642)
							(end 0.1778 -0.2794)
						)
					)
					(width 0)
					(fill yes)
				)
			)
		)
	)
	(footprint ""
		(layer "F.Cu")
		(at 413.166052 -183.620918)
		(property "Reference" "TP107"
			(at 0 0 0)
			(layer "F.SilkS")
			(hide yes)
			(effects
				(font
					(size 1.27 1.27)
				)
			)
		)
		(property "Value" "TPAD32-GP"
			(at -0.0508 -1.6764 0)
			(unlocked yes)
			(layer "F.Fab")
			(hide yes)
			(effects
				(font
					(size 1.016 1.016)
					(thickness 0.1524)
				)
			)
		)
		(property "Device Type" "TPAD32"
			(at -0.0508 -3.2004 0)
			(unlocked yes)
			(layer "F.Fab")
			(hide yes)
			(effects
				(font
					(size 1.016 1.016)
					(thickness 0.1524)
				)
			)
		)
		(duplicate_pad_numbers_are_jumpers no)
		(fp_poly
			(pts
				(arc
					(start 0.4064 0)
					(mid -0.4064 0)
					(end 0.4064 0)
				)
			)
			(stroke
				(width 0)
				(type default)
			)
			(fill no)
			(layer "F.CrtYd")
		)
		(fp_poly
			(pts
				(arc
					(start 0.7112 0)
					(mid -0.7112 0)
					(end 0.7112 0)
				)
			)
			(stroke
				(width 0)
				(type default)
			)
			(fill no)
			(layer "F.Fab")
		)
		(pad "1" smd circle
			(at 0 0)
			(size 0.8128 0.8128)
			(layers "F.Cu" "F.Mask" "F.Paste")
			(net "ACT_HDD_21")
		)
	)
	(footprint ""
		(layer "F.Cu")
		(at 377.308872 -293.892732)
		(property "Reference" "Q259"
			(at 0 0 0)
			(layer "F.SilkS")
			(hide yes)
			(effects
				(font
					(size 1.27 1.27)
				)
			)
		)
		(property "Value" "2N7002K-2-GP"
			(at 0.127 -8.9662 0)
			(unlocked yes)
			(layer "F.Fab")
			(hide yes)
			(effects
				(font
					(size 1.016 1.016)
					(thickness 0.1524)
				)
			)
		)
		(property "Device Type" "SOT23DGS2D4H44"
			(at 0.127 -10.4902 0)
			(unlocked yes)
			(layer "F.Fab")
			(hide yes)
			(effects
				(font
					(size 1.016 1.016)
					(thickness 0.1524)
				)
			)
		)
		(duplicate_pad_numbers_are_jumpers no)
		(fp_line
			(start -1.651 -1.778)
			(end -1.651 1.778)
			(stroke
				(width 0.1524)
				(type default)
			)
			(layer "F.SilkS")
		)
		(fp_line
			(start -1.651 1.778)
			(end 1.651 1.778)
			(stroke
				(width 0.1524)
				(type default)
			)
			(layer "F.SilkS")
		)
		(fp_line
			(start 1.651 -1.778)
			(end -1.651 -1.778)
			(stroke
				(width 0.1524)
				(type default)
			)
			(layer "F.SilkS")
		)
		(fp_line
			(start 1.651 1.778)
			(end 1.651 -1.778)
			(stroke
				(width 0.1524)
				(type default)
			)
			(layer "F.SilkS")
		)
		(fp_poly
			(pts
				(xy -1.778 1.8796) (xy -1.778 -1.8796) (xy 1.778 -1.8796) (xy 1.778 1.8796)
			)
			(stroke
				(width 0)
				(type default)
			)
			(fill no)
			(layer "F.CrtYd")
		)
		(fp_poly
			(pts
				(xy -1.778 1.8796) (xy -1.778 -1.8796) (xy 1.778 -1.8796) (xy 1.778 1.8796)
			)
			(stroke
				(width 0)
				(type default)
			)
			(fill no)
			(layer "F.Fab")
		)
		(pad "D" smd custom
			(at 0 -0.9525)
			(size 0.1905 0.1905)
			(layers "F.Cu" "F.Mask" "F.Paste")
			(net "FLT_HDD32_N")
			(options
				(clearance outline)
				(anchor circle)
			)
			(primitives
				(gr_poly
					(pts
						(arc
							(start -0.1778 0.5715)
							(mid -0.321484 0.511984)
							(end -0.381 0.3683)
						)
						(arc
							(start -0.381 -0.3683)
							(mid -0.321484 -0.511984)
							(end -0.1778 -0.5715)
						)
						(arc
							(start 0.1778 -0.5715)
							(mid 0.321484 -0.511984)
							(end 0.381 -0.3683)
						)
						(arc
							(start 0.381 0.3683)
							(mid 0.321484 0.511984)
							(end 0.1778 0.5715)
						)
					)
					(width 0)
					(fill yes)
				)
			)
		)
		(pad "G" smd custom
			(at -0.98425 0.9525)
			(size 0.1905 0.1905)
			(layers "F.Cu" "F.Mask" "F.Paste")
			(net "DRIVE_B_32_FLT_LED")
			(options
				(clearance outline)
				(anchor circle)
			)
			(primitives
				(gr_poly
					(pts
						(arc
							(start -0.1778 0.5715)
							(mid -0.321484 0.511984)
							(end -0.381 0.3683)
						)
						(arc
							(start -0.381 -0.3683)
							(mid -0.321484 -0.511984)
							(end -0.1778 -0.5715)
						)
						(arc
							(start 0.1778 -0.5715)
							(mid 0.321484 -0.511984)
							(end 0.381 -0.3683)
						)
						(arc
							(start 0.381 0.3683)
							(mid 0.321484 0.511984)
							(end 0.1778 0.5715)
						)
					)
					(width 0)
					(fill yes)
				)
			)
		)
		(pad "S" smd custom
			(at 0.98425 0.9525)
			(size 0.1905 0.1905)
			(layers "F.Cu" "F.Mask" "F.Paste")
			(net "GND")
			(options
				(clearance outline)
				(anchor circle)
			)
			(primitives
				(gr_poly
					(pts
						(arc
							(start -0.1778 0.5715)
							(mid -0.321484 0.511984)
							(end -0.381 0.3683)
						)
						(arc
							(start -0.381 -0.3683)
							(mid -0.321484 -0.511984)
							(end -0.1778 -0.5715)
						)
						(arc
							(start 0.1778 -0.5715)
							(mid 0.321484 -0.511984)
							(end 0.381 -0.3683)
						)
						(arc
							(start 0.381 0.3683)
							(mid 0.321484 0.511984)
							(end 0.1778 0.5715)
						)
					)
					(width 0)
					(fill yes)
				)
			)
		)
	)
)
